# T6G (Grand Teton) — schematic netlist excerpt (pin names and nets, part order shuffled) for the footprints in the layout excerpt that follows; sources: Cadence DE-HDL packaged netlist, KiCad conversion of 04192023_DAF0TMB3IC0_F0TG_MB_C_brd_V02_OCP.brd

R5015  Q_RES  1K 1% EMPTY  pkg 0402LF  page 159 : A = PVDD11_S3_P0 ; B = I3C_SCM_0_R_SDA
R465  Q_RES  49.9 1% CHIP  pkg 0402LF  page 29 : A = SPI_CPU0_D1 ; B = SPI_CPU0_R_D1

(kicad_pcb
	(version 20260206)
	(generator "pcbnew")
	(generator_version "10.0")
	(general
		(thickness 1.6)
		(legacy_teardrops no)
	)
	(paper "A4")
	(title_block
		(title "04192023_DAF0TMB3IC0_F0TG_MB_C_brd_V02_OCP.brd")
		(comment 1 "Grand Teton / footprints 2986-2987 of 8354")
	)
	(layers
		(0 "F.Cu" signal "TOP")
		(4 "In1.Cu" signal "GND")
		(6 "In2.Cu" signal "IN1")
		(8 "In3.Cu" signal "GND1")
		(10 "In4.Cu" signal "IN2")
		(12 "In5.Cu" signal "GND2")
		(14 "In6.Cu" signal "IN3")
		(16 "In7.Cu" signal "GND3")
		(18 "In8.Cu" signal "VCC")
		(20 "In9.Cu" signal "VCC1")
		(22 "In10.Cu" signal "GND4")
		(24 "In11.Cu" signal "IN4")
		(26 "In12.Cu" signal "GND5")
		(28 "In13.Cu" signal "IN5")
		(30 "In14.Cu" signal "GND6")
		(32 "In15.Cu" signal "IN6")
		(34 "In16.Cu" signal "GND7")
		(2 "B.Cu" signal "BOTTOM")
		(9 "F.Adhes" user "F.Adhesive")
		(11 "B.Adhes" user "B.Adhesive")
		(13 "F.Paste" user "Package Geometry/Pastemask Top")
		(15 "B.Paste" user "Package Geometry/Pastemask Bottom")
		(5 "F.SilkS" user "Ref Des/Silkscreen Top")
		(7 "B.SilkS" user "Ref Des/Silkscreen Bottom")
		(1 "F.Mask" user "Board Geometry/Soldermask Top")
		(3 "B.Mask" user "Board Geometry/Soldermask Bottom")
		(17 "Dwgs.User" user "User.Drawings")
		(19 "Cmts.User" user "User.Comments")
		(21 "Eco1.User" user "User.Eco1")
		(23 "Eco2.User" user "User.Eco2")
		(25 "Edge.Cuts" user "Board Geometry/Outline")
		(27 "Margin" user)
		(31 "F.CrtYd" user "Package Geometry/Place Bound Top")
		(29 "B.CrtYd" user "Package Geometry/Place Bound Bottom")
		(35 "F.Fab" user "Ref Des/Assembly Top")
		(33 "B.Fab" user "Ref Des/Assembly Bottom")
	)
	(footprint ""
		(layer "F.Cu")
		(at 305.082448 -149.210522 180)
		(property "Reference" "R5015"
			(at 0 0 180)
			(layer "F.SilkS")
			(hide yes)
			(effects
				(font
					(size 1.27 1.27)
				)
			)
		)
		(property "Value" ""
			(at 0 0 180)
			(layer "F.Fab")
			(effects
				(font
					(size 1.27 1.27)
				)
			)
		)
		(duplicate_pad_numbers_are_jumpers no)
		(fp_line
			(start 0.7874 0.4064)
			(end -0.7874 0.4064)
			(stroke
				(width 0.1524)
				(type default)
			)
			(layer "F.SilkS")
		)
		(fp_line
			(start 0.7874 -0.4064)
			(end 0.7874 0.4064)
			(stroke
				(width 0.1524)
				(type default)
			)
			(layer "F.SilkS")
		)
		(fp_line
			(start -0.7874 0.4064)
			(end -0.7874 -0.4064)
			(stroke
				(width 0.1524)
				(type default)
			)
			(layer "F.SilkS")
		)
		(fp_line
			(start -0.7874 -0.4064)
			(end 0.7874 -0.4064)
			(stroke
				(width 0.1524)
				(type default)
			)
			(layer "F.SilkS")
		)
		(fp_line
			(start 0.67945 0.3048)
			(end 0.120396 0.3048)
			(stroke
				(width 0.1)
				(type default)
			)
			(layer "F.Fab")
		)
		(fp_line
			(start 0.67945 -0.3048)
			(end 0.67945 0.3048)
			(stroke
				(width 0.1)
				(type default)
			)
			(layer "F.Fab")
		)
		(fp_line
			(start 0.12065 -0.2794)
			(end 0.12065 -0.3048)
			(stroke
				(width 0.1)
				(type default)
			)
			(layer "F.Fab")
		)
		(fp_line
			(start 0.12065 -0.3048)
			(end 0.67945 -0.3048)
			(stroke
				(width 0.1)
				(type default)
			)
			(layer "F.Fab")
		)
		(fp_line
			(start 0.120396 0.3048)
			(end 0.120396 0.2794)
			(stroke
				(width 0.1)
				(type default)
			)
			(layer "F.Fab")
		)
		(fp_line
			(start 0.120396 0.2794)
			(end -0.12065 0.2794)
			(stroke
				(width 0.1)
				(type default)
			)
			(layer "F.Fab")
		)
		(fp_line
			(start -0.12065 0.3048)
			(end -0.67945 0.3048)
			(stroke
				(width 0.1)
				(type default)
			)
			(layer "F.Fab")
		)
		(fp_line
			(start -0.12065 0.2794)
			(end -0.12065 0.3048)
			(stroke
				(width 0.1)
				(type default)
			)
			(layer "F.Fab")
		)
		(fp_line
			(start -0.12065 -0.2794)
			(end 0.12065 -0.2794)
			(stroke
				(width 0.1)
				(type default)
			)
			(layer "F.Fab")
		)
		(fp_line
			(start -0.12065 -0.305054)
			(end -0.12065 -0.2794)
			(stroke
				(width 0.1)
				(type default)
			)
			(layer "F.Fab")
		)
		(fp_line
			(start -0.67945 0.3048)
			(end -0.67945 -0.305054)
			(stroke
				(width 0.1)
				(type default)
			)
			(layer "F.Fab")
		)
		(fp_line
			(start -0.67945 -0.305054)
			(end -0.12065 -0.305054)
			(stroke
				(width 0.1)
				(type default)
			)
			(layer "F.Fab")
		)
		(pad "1" smd circle
			(at -0.40005 0 180)
			(size 0 0)
			(layers "F.Cu" "F.Mask" "F.Paste")
			(net "PVDD11_S3_P0")
		)
		(pad "2" smd circle
			(at 0.40005 0 180)
			(size 0 0)
			(layers "F.Cu" "F.Mask" "F.Paste")
			(net "I3C_SCM_0_R_SDA")
		)
	)
	(footprint ""
		(layer "F.Cu")
		(at 399.362168 -322.930012 180)
		(property "Reference" "R465"
			(at 0 0 180)
			(layer "F.SilkS")
			(hide yes)
			(effects
				(font
					(size 1.27 1.27)
				)
			)
		)
		(property "Value" ""
			(at 0 0 180)
			(layer "F.Fab")
			(effects
				(font
					(size 1.27 1.27)
				)
			)
		)
		(duplicate_pad_numbers_are_jumpers no)
		(fp_line
			(start 0.7874 0.4064)
			(end -0.7874 0.4064)
			(stroke
				(width 0.1524)
				(type default)
			)
			(layer "F.SilkS")
		)
		(fp_line
			(start 0.7874 -0.4064)
			(end 0.7874 0.4064)
			(stroke
				(width 0.1524)
				(type default)
			)
			(layer "F.SilkS")
		)
		(fp_line
			(start -0.7874 0.4064)
			(end -0.7874 -0.4064)
			(stroke
				(width 0.1524)
				(type default)
			)
			(layer "F.SilkS")
		)
		(fp_line
			(start -0.7874 -0.4064)
			(end 0.7874 -0.4064)
			(stroke
				(width 0.1524)
				(type default)
			)
			(layer "F.SilkS")
		)
		(fp_line
			(start 0.67945 0.3048)
			(end 0.120396 0.3048)
			(stroke
				(width 0.1)
				(type default)
			)
			(layer "F.Fab")
		)
		(fp_line
			(start 0.67945 -0.3048)
			(end 0.67945 0.3048)
			(stroke
				(width 0.1)
				(type default)
			)
			(layer "F.Fab")
		)
		(fp_line
			(start 0.12065 -0.2794)
			(end 0.12065 -0.3048)
			(stroke
				(width 0.1)
				(type default)
			)
			(layer "F.Fab")
		)
		(fp_line
			(start 0.12065 -0.3048)
			(end 0.67945 -0.3048)
			(stroke
				(width 0.1)
				(type default)
			)
			(layer "F.Fab")
		)
		(fp_line
			(start 0.120396 0.3048)
			(end 0.120396 0.2794)
			(stroke
				(width 0.1)
				(type default)
			)
			(layer "F.Fab")
		)
		(fp_line
			(start 0.120396 0.2794)
			(end -0.12065 0.2794)
			(stroke
				(width 0.1)
				(type default)
			)
			(layer "F.Fab")
		)
		(fp_line
			(start -0.12065 0.3048)
			(end -0.67945 0.3048)
			(stroke
				(width 0.1)
				(type default)
			)
			(layer "F.Fab")
		)
		(fp_line
			(start -0.12065 0.2794)
			(end -0.12065 0.3048)
			(stroke
				(width 0.1)
				(type default)
			)
			(layer "F.Fab")
		)
		(fp_line
			(start -0.12065 -0.2794)
			(end 0.12065 -0.2794)
			(stroke
				(width 0.1)
				(type default)
			)
			(layer "F.Fab")
		)
		(fp_line
			(start -0.12065 -0.305054)
			(end -0.12065 -0.2794)
			(stroke
				(width 0.1)
				(type default)
			)
			(layer "F.Fab")
		)
		(fp_line
			(start -0.67945 0.3048)
			(end -0.67945 -0.305054)
			(stroke
				(width 0.1)
				(type default)
			)
			(layer "F.Fab")
		)
		(fp_line
			(start -0.67945 -0.305054)
			(end -0.12065 -0.305054)
			(stroke
				(width 0.1)
				(type default)
			)
			(layer "F.Fab")
		)
		(pad "1" smd circle
			(at -0.40005 0 180)
			(size 0 0)
			(layers "F.Cu" "F.Mask" "F.Paste")
			(net "SPI_CPU0_D1")
		)
		(pad "2" smd circle
			(at 0.40005 0 180)
			(size 0 0)
			(layers "F.Cu" "F.Mask" "F.Paste")
			(net "SPI_CPU0_R_D1")
		)
	)
)
